# T6G (Grand Teton) — schematic netlist excerpt (pin names and nets, part order shuffled) for the footprints in the layout excerpt that follows; sources: Cadence DE-HDL packaged netlist, KiCad conversion of 04192023_DAF0TMB3IC0_F0TG_MB_C_brd_V02_OCP.brd

C2608  Q_CAP  22UF 4V 20% X6S  pkg C0402  page 70 : A = PVDD11_S3_P0 ; B = GND
C3907  Q_CAP  22UF 4V 20% X6S  pkg C0402  page 72 : A = PVDDCR_SOC_P1 ; B = GND

(kicad_pcb
	(version 20260206)
	(generator "pcbnew")
	(generator_version "10.0")
	(general
		(thickness 1.6)
		(legacy_teardrops no)
	)
	(paper "A4")
	(title_block
		(title "04192023_DAF0TMB3IC0_F0TG_MB_C_brd_V02_OCP.brd")
		(comment 1 "Grand Teton / footprints 6402-6403 of 8354")
	)
	(layers
		(0 "F.Cu" signal "TOP")
		(4 "In1.Cu" signal "GND")
		(6 "In2.Cu" signal "IN1")
		(8 "In3.Cu" signal "GND1")
		(10 "In4.Cu" signal "IN2")
		(12 "In5.Cu" signal "GND2")
		(14 "In6.Cu" signal "IN3")
		(16 "In7.Cu" signal "GND3")
		(18 "In8.Cu" signal "VCC")
		(20 "In9.Cu" signal "VCC1")
		(22 "In10.Cu" signal "GND4")
		(24 "In11.Cu" signal "IN4")
		(26 "In12.Cu" signal "GND5")
		(28 "In13.Cu" signal "IN5")
		(30 "In14.Cu" signal "GND6")
		(32 "In15.Cu" signal "IN6")
		(34 "In16.Cu" signal "GND7")
		(2 "B.Cu" signal "BOTTOM")
		(9 "F.Adhes" user "F.Adhesive")
		(11 "B.Adhes" user "B.Adhesive")
		(13 "F.Paste" user "Package Geometry/Pastemask Top")
		(15 "B.Paste" user "Package Geometry/Pastemask Bottom")
		(5 "F.SilkS" user "Ref Des/Silkscreen Top")
		(7 "B.SilkS" user "Ref Des/Silkscreen Bottom")
		(1 "F.Mask" user "Board Geometry/Soldermask Top")
		(3 "B.Mask" user "Board Geometry/Soldermask Bottom")
		(17 "Dwgs.User" user "User.Drawings")
		(19 "Cmts.User" user "User.Comments")
		(21 "Eco1.User" user "User.Eco1")
		(23 "Eco2.User" user "User.Eco2")
		(25 "Edge.Cuts" user "Board Geometry/Outline")
		(27 "Margin" user)
		(31 "F.CrtYd" user "Package Geometry/Place Bound Top")
		(29 "B.CrtYd" user "Package Geometry/Place Bound Bottom")
		(35 "F.Fab" user "Ref Des/Assembly Top")
		(33 "B.Fab" user "Ref Des/Assembly Bottom")
	)
	(footprint ""
		(layer "B.Cu")
		(at 114.325908 -256.012442 -90)
		(property "Reference" "C3907"
			(at 0 0 90)
			(layer "B.SilkS")
			(hide yes)
			(effects
				(font
					(size 1.27 1.27)
				)
				(justify mirror)
			)
		)
		(property "Value" ""
			(at 0 0 90)
			(layer "B.Fab")
			(effects
				(font
					(size 1.27 1.27)
				)
				(justify mirror)
			)
		)
		(duplicate_pad_numbers_are_jumpers no)
		(fp_line
			(start -0.7874 0.4064)
			(end 0.7874 0.4064)
			(stroke
				(width 0.1524)
				(type default)
			)
			(layer "B.SilkS")
		)
		(fp_line
			(start 0.7874 0.4064)
			(end 0.7874 -0.4064)
			(stroke
				(width 0.1524)
				(type default)
			)
			(layer "B.SilkS")
		)
		(fp_line
			(start -0.7874 -0.4064)
			(end -0.7874 0.4064)
			(stroke
				(width 0.1524)
				(type default)
			)
			(layer "B.SilkS")
		)
		(fp_line
			(start 0.7874 -0.4064)
			(end -0.7874 -0.4064)
			(stroke
				(width 0.1524)
				(type default)
			)
			(layer "B.SilkS")
		)
		(fp_line
			(start -0.67945 0.3048)
			(end -0.120396 0.3048)
			(stroke
				(width 0.1)
				(type default)
			)
			(layer "B.Fab")
		)
		(fp_line
			(start -0.120396 0.3048)
			(end -0.120396 0.2794)
			(stroke
				(width 0.1)
				(type default)
			)
			(layer "B.Fab")
		)
		(fp_line
			(start 0.12065 0.3048)
			(end 0.67945 0.3048)
			(stroke
				(width 0.1)
				(type default)
			)
			(layer "B.Fab")
		)
		(fp_line
			(start 0.67945 0.3048)
			(end 0.67945 -0.305054)
			(stroke
				(width 0.1)
				(type default)
			)
			(layer "B.Fab")
		)
		(fp_line
			(start -0.120396 0.2794)
			(end 0.12065 0.2794)
			(stroke
				(width 0.1)
				(type default)
			)
			(layer "B.Fab")
		)
		(fp_line
			(start 0.12065 0.2794)
			(end 0.12065 0.3048)
			(stroke
				(width 0.1)
				(type default)
			)
			(layer "B.Fab")
		)
		(fp_line
			(start -0.12065 -0.2794)
			(end -0.12065 -0.3048)
			(stroke
				(width 0.1)
				(type default)
			)
			(layer "B.Fab")
		)
		(fp_line
			(start 0.12065 -0.2794)
			(end -0.12065 -0.2794)
			(stroke
				(width 0.1)
				(type default)
			)
			(layer "B.Fab")
		)
		(fp_line
			(start -0.67945 -0.3048)
			(end -0.67945 0.3048)
			(stroke
				(width 0.1)
				(type default)
			)
			(layer "B.Fab")
		)
		(fp_line
			(start -0.12065 -0.3048)
			(end -0.67945 -0.3048)
			(stroke
				(width 0.1)
				(type default)
			)
			(layer "B.Fab")
		)
		(fp_line
			(start 0.12065 -0.305054)
			(end 0.12065 -0.2794)
			(stroke
				(width 0.1)
				(type default)
			)
			(layer "B.Fab")
		)
		(fp_line
			(start 0.67945 -0.305054)
			(end 0.12065 -0.305054)
			(stroke
				(width 0.1)
				(type default)
			)
			(layer "B.Fab")
		)
		(pad "1" smd circle
			(at 0.40005 0 90)
			(size 0 0)
			(layers "B.Cu" "B.Mask" "B.Paste")
			(net "PVDDCR_SOC_P1")
		)
		(pad "2" smd circle
			(at -0.40005 0 90)
			(size 0 0)
			(layers "B.Cu" "B.Mask" "B.Paste")
			(net "GND")
		)
	)
	(footprint ""
		(layer "B.Cu")
		(at 352.501454 -264.35431)
		(property "Reference" "C2608"
			(at 0 0 0)
			(layer "B.SilkS")
			(hide yes)
			(effects
				(font
					(size 1.27 1.27)
				)
				(justify mirror)
			)
		)
		(property "Value" ""
			(at 0 0 0)
			(layer "B.Fab")
			(effects
				(font
					(size 1.27 1.27)
				)
				(justify mirror)
			)
		)
		(duplicate_pad_numbers_are_jumpers no)
		(fp_line
			(start -0.7874 -0.4064)
			(end -0.7874 0.4064)
			(stroke
				(width 0.1524)
				(type default)
			)
			(layer "B.SilkS")
		)
		(fp_line
			(start -0.7874 0.4064)
			(end 0.7874 0.4064)
			(stroke
				(width 0.1524)
				(type default)
			)
			(layer "B.SilkS")
		)
		(fp_line
			(start 0.7874 -0.4064)
			(end -0.7874 -0.4064)
			(stroke
				(width 0.1524)
				(type default)
			)
			(layer "B.SilkS")
		)
		(fp_line
			(start 0.7874 0.4064)
			(end 0.7874 -0.4064)
			(stroke
				(width 0.1524)
				(type default)
			)
			(layer "B.SilkS")
		)
		(fp_line
			(start -0.67945 -0.3048)
			(end -0.67945 0.3048)
			(stroke
				(width 0.1)
				(type default)
			)
			(layer "B.Fab")
		)
		(fp_line
			(start -0.67945 0.3048)
			(end -0.120396 0.3048)
			(stroke
				(width 0.1)
				(type default)
			)
			(layer "B.Fab")
		)
		(fp_line
			(start -0.12065 -0.3048)
			(end -0.67945 -0.3048)
			(stroke
				(width 0.1)
				(type default)
			)
			(layer "B.Fab")
		)
		(fp_line
			(start -0.12065 -0.2794)
			(end -0.12065 -0.3048)
			(stroke
				(width 0.1)
				(type default)
			)
			(layer "B.Fab")
		)
		(fp_line
			(start -0.120396 0.2794)
			(end 0.12065 0.2794)
			(stroke
				(width 0.1)
				(type default)
			)
			(layer "B.Fab")
		)
		(fp_line
			(start -0.120396 0.3048)
			(end -0.120396 0.2794)
			(stroke
				(width 0.1)
				(type default)
			)
			(layer "B.Fab")
		)
		(fp_line
			(start 0.12065 -0.305054)
			(end 0.12065 -0.2794)
			(stroke
				(width 0.1)
				(type default)
			)
			(layer "B.Fab")
		)
		(fp_line
			(start 0.12065 -0.2794)
			(end -0.12065 -0.2794)
			(stroke
				(width 0.1)
				(type default)
			)
			(layer "B.Fab")
		)
		(fp_line
			(start 0.12065 0.2794)
			(end 0.12065 0.3048)
			(stroke
				(width 0.1)
				(type default)
			)
			(layer "B.Fab")
		)
		(fp_line
			(start 0.12065 0.3048)
			(end 0.67945 0.3048)
			(stroke
				(width 0.1)
				(type default)
			)
			(layer "B.Fab")
		)
		(fp_line
			(start 0.67945 -0.305054)
			(end 0.12065 -0.305054)
			(stroke
				(width 0.1)
				(type default)
			)
			(layer "B.Fab")
		)
		(fp_line
			(start 0.67945 0.3048)
			(end 0.67945 -0.305054)
			(stroke
				(width 0.1)
				(type default)
			)
			(layer "B.Fab")
		)
		(pad "1" smd circle
			(at 0.40005 0 180)
			(size 0 0)
			(layers "B.Cu" "B.Mask" "B.Paste")
			(net "PVDD11_S3_P0")
		)
		(pad "2" smd circle
			(at -0.40005 0 180)
			(size 0 0)
			(layers "B.Cu" "B.Mask" "B.Paste")
			(net "GND")
		)
	)
)
